(kicad_pcb
	(version 20260206)
	(generator "pcbnew")
	(generator_version "10.0")
	(general
		(thickness 1.6)
		(legacy_teardrops no)
	)
	(paper "A4")
	(title_block
		(title "03242023_DA0F0TMBIJ0_F0T_Motherboard_J_brd_V01_OCP.brd")
		(comment 1 "Grand Teton / footprints 3807-3812 of 6105")
	)
	(layers
		(0 "F.Cu" signal "TOP")
		(4 "In1.Cu" signal "GND")
		(6 "In2.Cu" signal "IN1")
		(8 "In3.Cu" signal "GND1")
		(10 "In4.Cu" signal "IN2")
		(12 "In5.Cu" signal "GND2")
		(14 "In6.Cu" signal "IN3")
		(16 "In7.Cu" signal "GND3")
		(18 "In8.Cu" signal "VCC")
		(20 "In9.Cu" signal "VCC1")
		(22 "In10.Cu" signal "GND4")
		(24 "In11.Cu" signal "IN4")
		(26 "In12.Cu" signal "GND5")
		(28 "In13.Cu" signal "IN5")
		(30 "In14.Cu" signal "GND6")
		(32 "In15.Cu" signal "IN6")
		(34 "In16.Cu" signal "GND7")
		(2 "B.Cu" signal "BOTTOM")
		(9 "F.Adhes" user "F.Adhesive")
		(11 "B.Adhes" user "B.Adhesive")
		(13 "F.Paste" user "Package Geometry/Pastemask Top")
		(15 "B.Paste" user "Package Geometry/Pastemask Bottom")
		(5 "F.SilkS" user "Ref Des/Silkscreen Top")
		(7 "B.SilkS" user "Ref Des/Silkscreen Bottom")
		(1 "F.Mask" user "Board Geometry/Soldermask Top")
		(3 "B.Mask" user "Board Geometry/Soldermask Bottom")
		(17 "Dwgs.User" user "User.Drawings")
		(19 "Cmts.User" user "User.Comments")
		(21 "Eco1.User" user "User.Eco1")
		(23 "Eco2.User" user "User.Eco2")
		(25 "Edge.Cuts" user "Board Geometry/Outline")
		(27 "Margin" user)
		(31 "F.CrtYd" user "Package Geometry/Place Bound Top")
		(29 "B.CrtYd" user "Package Geometry/Place Bound Bottom")
		(35 "F.Fab" user "Ref Des/Assembly Top")
		(33 "B.Fab" user "Ref Des/Assembly Bottom")
	)
	(footprint ""
		(layer "F.Cu")
		(at 164.52088 -43.525948)
		(property "Reference" "R487"
			(at 0 0 0)
			(layer "F.SilkS")
			(hide yes)
			(effects
				(font
					(size 1.27 1.27)
				)
			)
		)
		(property "Value" ""
			(at 0 0 0)
			(layer "F.Fab")
			(effects
				(font
					(size 1.27 1.27)
				)
			)
		)
		(duplicate_pad_numbers_are_jumpers no)
		(fp_line
			(start -0.7874 -0.4064)
			(end 0.7874 -0.4064)
			(stroke
				(width 0.1524)
				(type default)
			)
			(layer "F.SilkS")
		)
		(fp_line
			(start -0.7874 0.4064)
			(end -0.7874 -0.4064)
			(stroke
				(width 0.1524)
				(type default)
			)
			(layer "F.SilkS")
		)
		(fp_line
			(start 0.7874 -0.4064)
			(end 0.7874 0.4064)
			(stroke
				(width 0.1524)
				(type default)
			)
			(layer "F.SilkS")
		)
		(fp_line
			(start 0.7874 0.4064)
			(end -0.7874 0.4064)
			(stroke
				(width 0.1524)
				(type default)
			)
			(layer "F.SilkS")
		)
		(fp_line
			(start -0.67945 -0.305054)
			(end -0.12065 -0.305054)
			(stroke
				(width 0.1)
				(type default)
			)
			(layer "F.Fab")
		)
		(fp_line
			(start -0.67945 0.3048)
			(end -0.67945 -0.305054)
			(stroke
				(width 0.1)
				(type default)
			)
			(layer "F.Fab")
		)
		(fp_line
			(start -0.12065 -0.305054)
			(end -0.12065 -0.2794)
			(stroke
				(width 0.1)
				(type default)
			)
			(layer "F.Fab")
		)
		(fp_line
			(start -0.12065 -0.2794)
			(end 0.12065 -0.2794)
			(stroke
				(width 0.1)
				(type default)
			)
			(layer "F.Fab")
		)
		(fp_line
			(start -0.12065 0.2794)
			(end -0.12065 0.3048)
			(stroke
				(width 0.1)
				(type default)
			)
			(layer "F.Fab")
		)
		(fp_line
			(start -0.12065 0.3048)
			(end -0.67945 0.3048)
			(stroke
				(width 0.1)
				(type default)
			)
			(layer "F.Fab")
		)
		(fp_line
			(start 0.120396 0.2794)
			(end -0.12065 0.2794)
			(stroke
				(width 0.1)
				(type default)
			)
			(layer "F.Fab")
		)
		(fp_line
			(start 0.120396 0.3048)
			(end 0.120396 0.2794)
			(stroke
				(width 0.1)
				(type default)
			)
			(layer "F.Fab")
		)
		(fp_line
			(start 0.12065 -0.3048)
			(end 0.67945 -0.3048)
			(stroke
				(width 0.1)
				(type default)
			)
			(layer "F.Fab")
		)
		(fp_line
			(start 0.12065 -0.2794)
			(end 0.12065 -0.3048)
			(stroke
				(width 0.1)
				(type default)
			)
			(layer "F.Fab")
		)
		(fp_line
			(start 0.67945 -0.3048)
			(end 0.67945 0.3048)
			(stroke
				(width 0.1)
				(type default)
			)
			(layer "F.Fab")
		)
		(fp_line
			(start 0.67945 0.3048)
			(end 0.120396 0.3048)
			(stroke
				(width 0.1)
				(type default)
			)
			(layer "F.Fab")
		)
		(pad "1" smd circle
			(at -0.40005 0)
			(size 0 0)
			(layers "F.Cu" "F.Mask" "F.Paste")
			(net "P3V3_AUX")
		)
		(pad "2" smd circle
			(at 0.40005 0)
			(size 0 0)
			(layers "F.Cu" "F.Mask" "F.Paste")
			(net "M2_SSD0_CLKREQ_EN_N_BUF")
		)
	)
	(footprint ""
		(layer "F.Cu")
		(at 432.798728 -57.916826 90)
		(property "Reference" "C1339"
			(at 0 0 90)
			(layer "F.SilkS")
			(hide yes)
			(effects
				(font
					(size 1.27 1.27)
				)
			)
		)
		(property "Value" ""
			(at 0 0 90)
			(layer "F.Fab")
			(effects
				(font
					(size 1.27 1.27)
				)
			)
		)
		(duplicate_pad_numbers_are_jumpers no)
		(fp_line
			(start 0.7874 -0.4064)
			(end 0.7874 0.4064)
			(stroke
				(width 0.1524)
				(type default)
			)
			(layer "F.SilkS")
		)
		(fp_line
			(start -0.7874 -0.4064)
			(end 0.7874 -0.4064)
			(stroke
				(width 0.1524)
				(type default)
			)
			(layer "F.SilkS")
		)
		(fp_line
			(start 0.7874 0.4064)
			(end -0.7874 0.4064)
			(stroke
				(width 0.1524)
				(type default)
			)
			(layer "F.SilkS")
		)
		(fp_line
			(start -0.7874 0.4064)
			(end -0.7874 -0.4064)
			(stroke
				(width 0.1524)
				(type default)
			)
			(layer "F.SilkS")
		)
		(fp_line
			(start -0.12065 -0.305054)
			(end -0.12065 -0.2794)
			(stroke
				(width 0.1)
				(type default)
			)
			(layer "F.Fab")
		)
		(fp_line
			(start -0.67945 -0.305054)
			(end -0.12065 -0.305054)
			(stroke
				(width 0.1)
				(type default)
			)
			(layer "F.Fab")
		)
		(fp_line
			(start 0.67945 -0.3048)
			(end 0.67945 0.3048)
			(stroke
				(width 0.1)
				(type default)
			)
			(layer "F.Fab")
		)
		(fp_line
			(start 0.12065 -0.3048)
			(end 0.67945 -0.3048)
			(stroke
				(width 0.1)
				(type default)
			)
			(layer "F.Fab")
		)
		(fp_line
			(start 0.12065 -0.2794)
			(end 0.12065 -0.3048)
			(stroke
				(width 0.1)
				(type default)
			)
			(layer "F.Fab")
		)
		(fp_line
			(start -0.12065 -0.2794)
			(end 0.12065 -0.2794)
			(stroke
				(width 0.1)
				(type default)
			)
			(layer "F.Fab")
		)
		(fp_line
			(start 0.120396 0.2794)
			(end -0.12065 0.2794)
			(stroke
				(width 0.1)
				(type default)
			)
			(layer "F.Fab")
		)
		(fp_line
			(start -0.12065 0.2794)
			(end -0.12065 0.3048)
			(stroke
				(width 0.1)
				(type default)
			)
			(layer "F.Fab")
		)
		(fp_line
			(start 0.67945 0.3048)
			(end 0.120396 0.3048)
			(stroke
				(width 0.1)
				(type default)
			)
			(layer "F.Fab")
		)
		(fp_line
			(start 0.120396 0.3048)
			(end 0.120396 0.2794)
			(stroke
				(width 0.1)
				(type default)
			)
			(layer "F.Fab")
		)
		(fp_line
			(start -0.12065 0.3048)
			(end -0.67945 0.3048)
			(stroke
				(width 0.1)
				(type default)
			)
			(layer "F.Fab")
		)
		(fp_line
			(start -0.67945 0.3048)
			(end -0.67945 -0.305054)
			(stroke
				(width 0.1)
				(type default)
			)
			(layer "F.Fab")
		)
		(pad "1" smd circle
			(at -0.40005 0 90)
			(size 0 0)
			(layers "F.Cu" "F.Mask" "F.Paste")
			(net "P3V3")
		)
		(pad "2" smd circle
			(at 0.40005 0 90)
			(size 0 0)
			(layers "F.Cu" "F.Mask" "F.Paste")
			(net "GND")
		)
	)
	(footprint ""
		(layer "F.Cu")
		(at 493.36833 -303.592992 90)
		(property "Reference" "X10"
			(at -3.481832 3.05562 90)
			(unlocked yes)
			(layer "F.SilkS")
			(effects
				(font
					(size 0.7874 0.5842)
					(thickness 0.1524)
				)
				(justify left)
			)
		)
		(property "Value" ""
			(at 0 0 90)
			(layer "F.Fab")
			(effects
				(font
					(size 1.27 1.27)
				)
			)
		)
		(property "Device Type" "TP_TDR_4P_FTS_TH-TP_TDR_4P_DIPA"
			(at 1.30175 1.27 180)
			(unlocked yes)
			(layer "F.Fab")
			(hide yes)
			(effects
				(font
					(size 0.635 0.4064)
					(thickness 0.1524)
				)
			)
		)
		(property "User Part Number" "N_A"
			(at 1.30175 1.27 180)
			(unlocked yes)
			(layer "Cmts.User")
			(hide yes)
			(effects
				(font
					(size 0.635 0.4064)
					(thickness 0.1524)
				)
			)
		)
		(duplicate_pad_numbers_are_jumpers no)
		(fp_line
			(start 2.54 -1.27)
			(end 0 -1.27)
			(stroke
				(width 0.1524)
				(type default)
			)
			(layer "F.SilkS")
		)
		(fp_line
			(start 0 -1.27)
			(end 0 -0.635)
			(stroke
				(width 0.1524)
				(type default)
			)
			(layer "F.SilkS")
		)
		(fp_line
			(start 2.54 -1.1303)
			(end 2.54 -1.27)
			(stroke
				(width 0.1524)
				(type default)
			)
			(layer "F.SilkS")
		)
		(fp_line
			(start 0 0.635)
			(end 0 1.905)
			(stroke
				(width 0.1524)
				(type default)
			)
			(layer "F.SilkS")
		)
		(fp_line
			(start 2.54 1.4097)
			(end 2.54 1.1303)
			(stroke
				(width 0.1524)
				(type default)
			)
			(layer "F.SilkS")
		)
		(fp_line
			(start 0 3.175)
			(end 0 3.81)
			(stroke
				(width 0.1524)
				(type default)
			)
			(layer "F.SilkS")
		)
		(fp_line
			(start 2.54 3.81)
			(end 2.54 3.6703)
			(stroke
				(width 0.1524)
				(type default)
			)
			(layer "F.SilkS")
		)
		(fp_line
			(start 0 3.81)
			(end 2.54 3.81)
			(stroke
				(width 0.1524)
				(type default)
			)
			(layer "F.SilkS")
		)
		(fp_poly
			(pts
				(xy -0.761746 0) (xy -2.285746 0.762) (xy -2.285746 -0.762)
			)
			(stroke
				(width 0)
				(type default)
			)
			(fill yes)
			(layer "F.SilkS")
		)
		(fp_line
			(start 2.54 -1.27)
			(end 0 -1.27)
			(stroke
				(width 0.1)
				(type default)
			)
			(layer "F.Fab")
		)
		(fp_line
			(start 0 -1.27)
			(end 0 3.81)
			(stroke
				(width 0.1)
				(type default)
			)
			(layer "F.Fab")
		)
		(fp_line
			(start 2.54 3.81)
			(end 2.54 -1.27)
			(stroke
				(width 0.1)
				(type default)
			)
			(layer "F.Fab")
		)
		(fp_line
			(start 0 3.81)
			(end 2.54 3.81)
			(stroke
				(width 0.1)
				(type default)
			)
			(layer "F.Fab")
		)
		(fp_poly
			(pts
				(xy -0.761746 0) (xy -2.285746 -0.762) (xy -2.285746 0.762)
			)
			(stroke
				(width 0)
				(type default)
			)
			(fill yes)
			(layer "F.Fab")
		)
		(pad "1" thru_hole circle
			(at 0 0 90)
			(size 1.0033 1.0033)
			(drill 0.249936)
			(layers "*.Cu" "*.Mask")
			(remove_unused_layers no)
			(net "TDR_DIFF_85_IN3_DN")
			(clearance 0.10795)
			(thermal_gap 0.10795)
			(padstack
				(mode front_inner_back)
				(layer "Inner"
					(shape circle)
					(size 0.8001 0.8001)
					(clearance 0.1524)
				)
				(layer "B.Cu"
					(shape circle)
					(size 1.0033 1.0033)
					(clearance 0.10795)
				)
			)
		)
		(pad "2" thru_hole circle
			(at 2.54 0 90)
			(size 1.9939 1.9939)
			(drill 0.249936)
			(layers "*.Cu" "*.Mask")
			(remove_unused_layers no)
			(net "T1_GND")
			(clearance 0.10795)
			(thermal_gap 0.10795)
			(padstack
				(mode front_inner_back)
				(layer "Inner"
					(shape circle)
					(size 0.8001 0.8001)
					(clearance 0.1524)
				)
				(layer "B.Cu"
					(shape circle)
					(size 1.9939 1.9939)
					(clearance 0.10795)
				)
			)
		)
		(pad "3" thru_hole circle
			(at 2.54 2.54 90)
			(size 1.9939 1.9939)
			(drill 0.249936)
			(layers "*.Cu" "*.Mask")
			(remove_unused_layers no)
			(net "T1_GND")
			(clearance 0.10795)
			(thermal_gap 0.10795)
			(padstack
				(mode front_inner_back)
				(layer "Inner"
					(shape circle)
					(size 0.8001 0.8001)
					(clearance 0.1524)
				)
				(layer "B.Cu"
					(shape circle)
					(size 1.9939 1.9939)
					(clearance 0.10795)
				)
			)
		)
		(pad "4" thru_hole circle
			(at 0 2.54 90)
			(size 1.0033 1.0033)
			(drill 0.249936)
			(layers "*.Cu" "*.Mask")
			(remove_unused_layers no)
			(net "TDR_DIFF_85_IN3_DP")
			(clearance 0.10795)
			(thermal_gap 0.10795)
			(padstack
				(mode front_inner_back)
				(layer "Inner"
					(shape circle)
					(size 0.8001 0.8001)
					(clearance 0.1524)
				)
				(layer "B.Cu"
					(shape circle)
					(size 1.0033 1.0033)
					(clearance 0.10795)
				)
			)
		)
	)
	(footprint ""
		(layer "F.Cu")
		(at 10.339832 -347.699838)
		(property "Reference" "H97"
			(at -5.945632 -4.789932 0)
			(unlocked yes)
			(layer "F.SilkS")
			(effects
				(font
					(size 0.7874 0.5842)
					(thickness 0.1524)
				)
				(justify left)
			)
		)
		(property "Value" ""
			(at 0 0 0)
			(layer "F.Fab")
			(effects
				(font
					(size 1.27 1.27)
				)
			)
		)
		(duplicate_pad_numbers_are_jumpers no)
		(pad "1" thru_hole circle
			(at 0 0)
			(size 10.0076 10.0076)
			(drill 5.6134)
			(layers "*.Cu" "*.Mask")
			(remove_unused_layers no)
			(net "GND")
			(clearance -1.9431)
		)
	)
	(footprint ""
		(layer "F.Cu")
		(at 344.899488 -324.445376)
		(property "Reference" "PL114"
			(at -9.220708 5.188458 0)
			(unlocked yes)
			(layer "F.SilkS")
			(effects
				(font
					(size 0.7874 0.5842)
					(thickness 0.1524)
				)
				(justify left)
			)
		)
		(property "Value" ""
			(at 0 0 0)
			(layer "F.Fab")
			(effects
				(font
					(size 1.27 1.27)
				)
			)
		)
		(duplicate_pad_numbers_are_jumpers no)
		(fp_line
			(start -3.750056 -5.500116)
			(end -2.393442 -5.500116)
			(stroke
				(width 0.1524)
				(type default)
			)
			(layer "F.SilkS")
		)
		(fp_line
			(start -3.750056 5.500116)
			(end -3.750056 -5.500116)
			(stroke
				(width 0.1524)
				(type default)
			)
			(layer "F.SilkS")
		)
		(fp_line
			(start -2.393442 5.500116)
			(end -3.750056 5.500116)
			(stroke
				(width 0.1524)
				(type default)
			)
			(layer "F.SilkS")
		)
		(fp_line
			(start 2.393442 5.500116)
			(end 3.750056 5.500116)
			(stroke
				(width 0.1524)
				(type default)
			)
			(layer "F.SilkS")
		)
		(fp_line
			(start 3.750056 -5.500116)
			(end 2.393442 -5.500116)
			(stroke
				(width 0.1524)
				(type default)
			)
			(layer "F.SilkS")
		)
		(fp_line
			(start 3.750056 -4.576572)
			(end 3.750056 -5.500116)
			(stroke
				(width 0.1524)
				(type default)
			)
			(layer "F.SilkS")
		)
		(fp_line
			(start 3.750056 5.500116)
			(end 3.750056 -3.687572)
			(stroke
				(width 0.1524)
				(type default)
			)
			(layer "F.SilkS")
		)
		(fp_poly
			(pts
				(xy -3.280664 -7.074154) (xy -2.921508 -5.996432) (xy -3.998976 -6.355842)
			)
			(stroke
				(width 0)
				(type default)
			)
			(fill yes)
			(layer "F.SilkS")
		)
		(fp_line
			(start -3.750056 -5.500116)
			(end -3.750056 5.500116)
			(stroke
				(width 0.1)
				(type default)
			)
			(layer "F.Fab")
		)
		(fp_line
			(start -3.750056 5.500116)
			(end 3.750056 5.500116)
			(stroke
				(width 0.1)
				(type default)
			)
			(layer "F.Fab")
		)
		(fp_line
			(start 3.750056 -5.500116)
			(end -3.750056 -5.500116)
			(stroke
				(width 0.1)
				(type default)
			)
			(layer "F.Fab")
		)
		(fp_line
			(start 3.750056 5.500116)
			(end 3.750056 -5.500116)
			(stroke
				(width 0.1)
				(type default)
			)
			(layer "F.Fab")
		)
		(fp_poly
			(pts
				(xy -4.9276 -4.757928) (xy -4.9276 -3.741928) (xy -3.9116 -4.249928)
			)
			(stroke
				(width 0)
				(type default)
			)
			(fill yes)
			(layer "F.Fab")
		)
		(pad "1" smd rect
			(at 0 -4.249928 270)
			(size 2.413 4.5212)
			(layers "F.Cu" "F.Mask" "F.Paste")
			(net "SW_PVCCIN_CPU0_SW1")
		)
		(pad "2" smd rect
			(at 0 -1.175004 270)
			(size 1.3716 4.5212)
			(layers "F.Cu" "F.Mask" "F.Paste")
			(net "IND_P0_CPL1")
		)
		(pad "3" smd rect
			(at 0 1.175004 270)
			(size 1.3716 4.5212)
			(layers "F.Cu" "F.Mask" "F.Paste")
			(net "IND_P0_CPL2")
		)
		(pad "4" smd rect
			(at 0 4.249928 270)
			(size 2.413 4.5212)
			(layers "F.Cu" "F.Mask" "F.Paste")
			(net "PVCCIN_CPU0")
		)
	)
	(footprint ""
		(layer "F.Cu")
		(at 457.7461 -381.24892 -90)
		(property "Reference" "PC1853"
			(at 0 0 270)
			(layer "F.SilkS")
			(hide yes)
			(effects
				(font
					(size 1.27 1.27)
				)
			)
		)
		(property "Value" ""
			(at 0 0 270)
			(layer "F.Fab")
			(effects
				(font
					(size 1.27 1.27)
				)
			)
		)
		(duplicate_pad_numbers_are_jumpers no)
		(fp_line
			(start -0.7874 0.4064)
			(end -0.7874 -0.4064)
			(stroke
				(width 0.1524)
				(type default)
			)
			(layer "F.SilkS")
		)
		(fp_line
			(start 0.7874 0.4064)
			(end -0.7874 0.4064)
			(stroke
				(width 0.1524)
				(type default)
			)
			(layer "F.SilkS")
		)
		(fp_line
			(start -0.7874 -0.4064)
			(end 0.7874 -0.4064)
			(stroke
				(width 0.1524)
				(type default)
			)
			(layer "F.SilkS")
		)
		(fp_line
			(start 0.7874 -0.4064)
			(end 0.7874 0.4064)
			(stroke
				(width 0.1524)
				(type default)
			)
			(layer "F.SilkS")
		)
		(fp_line
			(start -0.67945 0.3048)
			(end -0.67945 -0.305054)
			(stroke
				(width 0.1)
				(type default)
			)
			(layer "F.Fab")
		)
		(fp_line
			(start -0.12065 0.3048)
			(end -0.67945 0.3048)
			(stroke
				(width 0.1)
				(type default)
			)
			(layer "F.Fab")
		)
		(fp_line
			(start 0.120396 0.3048)
			(end 0.120396 0.2794)
			(stroke
				(width 0.1)
				(type default)
			)
			(layer "F.Fab")
		)
		(fp_line
			(start 0.67945 0.3048)
			(end 0.120396 0.3048)
			(stroke
				(width 0.1)
				(type default)
			)
			(layer "F.Fab")
		)
		(fp_line
			(start -0.12065 0.2794)
			(end -0.12065 0.3048)
			(stroke
				(width 0.1)
				(type default)
			)
			(layer "F.Fab")
		)
		(fp_line
			(start 0.120396 0.2794)
			(end -0.12065 0.2794)
			(stroke
				(width 0.1)
				(type default)
			)
			(layer "F.Fab")
		)
		(fp_line
			(start -0.12065 -0.2794)
			(end 0.12065 -0.2794)
			(stroke
				(width 0.1)
				(type default)
			)
			(layer "F.Fab")
		)
		(fp_line
			(start 0.12065 -0.2794)
			(end 0.12065 -0.3048)
			(stroke
				(width 0.1)
				(type default)
			)
			(layer "F.Fab")
		)
		(fp_line
			(start 0.12065 -0.3048)
			(end 0.67945 -0.3048)
			(stroke
				(width 0.1)
				(type default)
			)
			(layer "F.Fab")
		)
		(fp_line
			(start 0.67945 -0.3048)
			(end 0.67945 0.3048)
			(stroke
				(width 0.1)
				(type default)
			)
			(layer "F.Fab")
		)
		(fp_line
			(start -0.67945 -0.305054)
			(end -0.12065 -0.305054)
			(stroke
				(width 0.1)
				(type default)
			)
			(layer "F.Fab")
		)
		(fp_line
			(start -0.12065 -0.305054)
			(end -0.12065 -0.2794)
			(stroke
				(width 0.1)
				(type default)
			)
			(layer "F.Fab")
		)
		(pad "1" smd circle
			(at -0.40005 0 270)
			(size 0 0)
			(layers "F.Cu" "F.Mask" "F.Paste")
			(net "P5V_AUX_REF")
		)
		(pad "2" smd circle
			(at 0.40005 0 270)
			(size 0 0)
			(layers "F.Cu" "F.Mask" "F.Paste")
			(net "GND")
		)
	)
)
